(kicad_pcb
	(version 20241229)
	(generator "pcbnew")
	(generator_version "9.0")
	(general
		(thickness 1.294)
		(legacy_teardrops no)
	)
	(paper "A3")
	(title_block
		(title "Kintex 410T devboard")
		(date "2024-04-03")
		(rev "1.1.2")
		(comment 9 "footprints 377-377 of 975")
	)
	(layers
		(0 "F.Cu" mixed)
		(4 "In1.Cu" power)
		(6 "In2.Cu" power)
		(8 "In3.Cu" mixed)
		(10 "In4.Cu" power)
		(12 "In5.Cu" mixed)
		(14 "In6.Cu" power)
		(16 "In7.Cu" mixed)
		(18 "In8.Cu" power)
		(2 "B.Cu" mixed)
		(9 "F.Adhes" user "F.Adhesive")
		(11 "B.Adhes" user "B.Adhesive")
		(13 "F.Paste" user)
		(15 "B.Paste" user)
		(5 "F.SilkS" user "F.Silkscreen")
		(7 "B.SilkS" user "B.Silkscreen")
		(1 "F.Mask" user)
		(3 "B.Mask" user)
		(17 "Dwgs.User" user "User.Drawings")
		(19 "Cmts.User" user "User.Comments")
		(21 "Eco1.User" user "User.Eco1")
		(23 "Eco2.User" user "User.Eco2")
		(25 "Edge.Cuts" user)
		(27 "Margin" user)
		(31 "F.CrtYd" user "F.Courtyard")
		(29 "B.CrtYd" user "B.Courtyard")
		(35 "F.Fab" user)
		(33 "B.Fab" user)
	)
	(footprint "antmicro-footprints:0895-2C1R-GVH"
		(locked yes)
		(layer "F.Cu")
		(at 261.5 161.5 90)
		(property "Reference" "J15"
			(at 6.85 -27.9 90)
			(layer "F.SilkS")
			(effects
				(font
					(size 0.7 0.7)
					(thickness 0.15)
				)
				(justify left bottom)
			)
		)
		(property "Value" "0895-2C1R-GVH"
			(at 0 -2.5 90)
			(layer "F.Fab")
			(effects
				(font
					(size 0.7 0.7)
					(thickness 0.15)
				)
				(justify left bottom)
			)
		)
		(property "Description" "Modular connector with magnetics"
			(at 0 0 90)
			(layer "F.Fab")
			(hide yes)
			(effects
				(font
					(size 1.27 1.27)
					(thickness 0.15)
				)
			)
		)
		(property "Author" "Antmicro"
			(at 423 -100 0)
			(layer "F.Fab")
			(hide yes)
			(effects
				(font
					(size 1 1)
					(thickness 0.15)
				)
			)
		)
		(property "License" "Apache-2.0"
			(at 423 -100 0)
			(layer "F.Fab")
			(hide yes)
			(effects
				(font
					(size 1 1)
					(thickness 0.15)
				)
			)
		)
		(property "MPN" "0895-2C1R-GVH"
			(at 423 -100 0)
			(layer "F.Fab")
			(hide yes)
			(effects
				(font
					(size 1 1)
					(thickness 0.15)
				)
			)
		)
		(property "Manufacturer" "Bel Fuse"
			(at 423 -100 0)
			(layer "F.Fab")
			(hide yes)
			(effects
				(font
					(size 1 1)
					(thickness 0.15)
				)
			)
		)
		(sheetname "HDMI + Ethernet")
		(sheetfile "hdmi-ethernet.kicad_sch")
		(attr through_hole)
		(fp_line
			(start 8.585 -27.61)
			(end -8.587 -27.61)
			(stroke
				(width 0.15)
				(type solid)
			)
			(layer "F.SilkS")
		)
		(fp_line
			(start 8.585 -24.258)
			(end 8.585 -12.93)
			(stroke
				(width 0.15)
				(type solid)
			)
			(layer "F.SilkS")
		)
		(fp_line
			(start -8.587 -24.258)
			(end -8.587 -17.02)
			(stroke
				(width 0.15)
				(type solid)
			)
			(layer "F.SilkS")
		)
		(fp_line
			(start -8.587 -13.971)
			(end -8.587 3.072)
			(stroke
				(width 0.15)
				(type solid)
			)
			(layer "F.SilkS")
		)
		(fp_line
			(start 8.585 -9.907)
			(end 8.585 3.047)
			(stroke
				(width 0.15)
				(type solid)
			)
			(layer "F.SilkS")
		)
		(fp_line
			(start 7.11 4.825)
			(end 7.11 7.365)
			(stroke
				(width 0.15)
				(type solid)
			)
			(layer "F.SilkS")
		)
		(fp_line
			(start -7.112 4.825)
			(end 7.11 4.825)
			(stroke
				(width 0.15)
				(type solid)
			)
			(layer "F.SilkS")
		)
		(fp_line
			(start -7.112 4.825)
			(end -7.112 7.365)
			(stroke
				(width 0.15)
				(type solid)
			)
			(layer "F.SilkS")
		)
		(fp_line
			(start 8.585 6.07)
			(end 8.585 7.365)
			(stroke
				(width 0.15)
				(type solid)
			)
			(layer "F.SilkS")
		)
		(fp_line
			(start -8.587 6.094)
			(end -8.587 7.365)
			(stroke
				(width 0.15)
				(type solid)
			)
			(layer "F.SilkS")
		)
		(fp_line
			(start 8.585 7.365)
			(end 7.11 7.365)
			(stroke
				(width 0.15)
				(type solid)
			)
			(layer "F.SilkS")
		)
		(fp_line
			(start -8.587 7.365)
			(end -7.112 7.365)
			(stroke
				(width 0.15)
				(type solid)
			)
			(layer "F.SilkS")
		)
		(fp_circle
			(center -10.51 -4.734)
			(end -10.41 -4.734)
			(stroke
				(width 0.15)
				(type solid)
			)
			(fill no)
			(layer "F.SilkS")
		)
		(fp_rect
			(start -10.856 -28.622)
			(end 10.854 12.316)
			(stroke
				(width 0.05)
				(type solid)
			)
			(fill no)
			(layer "F.CrtYd")
		)
		(fp_line
			(start 8.585 -27.61)
			(end -8.587 -27.61)
			(stroke
				(width 0.15)
				(type solid)
			)
			(layer "F.Fab")
		)
		(fp_line
			(start 8.585 -27.61)
			(end 8.585 10.743)
			(stroke
				(width 0.15)
				(type solid)
			)
			(layer "F.Fab")
		)
		(fp_line
			(start -8.587 -27.61)
			(end -8.587 10.743)
			(stroke
				(width 0.15)
				(type solid)
			)
			(layer "F.Fab")
		)
		(fp_line
			(start -8.587 10.743)
			(end 8.585 10.743)
			(stroke
				(width 0.15)
				(type solid)
			)
			(layer "F.Fab")
		)
		(fp_arc
			(start 8.499 0.497)
			(mid 9.441 5.613)
			(end 8.585 10.743)
			(stroke
				(width 0.15)
				(type solid)
			)
			(layer "F.Fab")
		)
		(fp_arc
			(start -8.587 10.743)
			(mid -9.443 5.613)
			(end -8.5 0.497)
			(stroke
				(width 0.15)
				(type solid)
			)
			(layer "F.Fab")
		)
		(fp_circle
			(center -10.51 -4.734)
			(end -10.41 -4.734)
			(stroke
				(width 0.15)
				(type solid)
			)
			(fill no)
			(layer "F.Fab")
		)
		(pad "" np_thru_hole circle
			(at -5.715 0 90)
			(size 3.2512 3.2512)
			(drill 3.2512)
			(layers "*.Cu" "*.Mask")
		)
		(pad "" np_thru_hole circle
			(at 5.714 0 90)
			(size 3.2512 3.2512)
			(drill 3.2512)
			(layers "*.Cu" "*.Mask")
		)
		(pad "1_1" thru_hole circle
			(at -3.302 -4.699 90)
			(size 1.524 1.524)
			(drill 1.016)
			(layers "*.Cu" "*.Mask")
			(remove_unused_layers no)
			(net 725 "/HDMI + Ethernet/ETH1_N")
			(pinfunction "TRD1-_1")
			(pintype "passive")
		)
		(pad "1_2" thru_hole circle
			(at 3.301 -4.699 90)
			(size 1.524 1.524)
			(drill 1.016)
			(layers "*.Cu" "*.Mask")
			(remove_unused_layers no)
			(net 853 "/HDMI + Ethernet/GBE4_N")
			(pinfunction "TRD1-_2")
			(pintype "passive")
		)
		(pad "2_1" thru_hole circle
			(at -2.032 -5.97 90)
			(size 1.524 1.524)
			(drill 1.016)
			(layers "*.Cu" "*.Mask")
			(remove_unused_layers no)
			(net 724 "/HDMI + Ethernet/ETH1_P")
			(pinfunction "TRD1+_1")
			(pintype "passive")
		)
		(pad "2_2" thru_hole circle
			(at 2.031 -5.97 90)
			(size 1.524 1.524)
			(drill 1.016)
			(layers "*.Cu" "*.Mask")
			(remove_unused_layers no)
			(net 854 "/HDMI + Ethernet/GBE4_P")
			(pinfunction "TRD1+_2")
			(pintype "passive")
		)
		(pad "3_1" thru_hole circle
			(at -3.302 -7.239 90)
			(size 1.524 1.524)
			(drill 1.016)
			(layers "*.Cu" "*.Mask")
			(remove_unused_layers no)
			(net 729 "/HDMI + Ethernet/ETH2_N")
			(pinfunction "TRD2-_1")
			(pintype "passive")
		)
		(pad "3_2" thru_hole circle
			(at 3.301 -7.239 90)
			(size 1.524 1.524)
			(drill 1.016)
			(layers "*.Cu" "*.Mask")
			(remove_unused_layers no)
			(net 855 "/HDMI + Ethernet/GBE3_N")
			(pinfunction "TRD2-_2")
			(pintype "passive")
		)
		(pad "4_1" thru_hole circle
			(at -2.032 -8.51 90)
			(size 1.524 1.524)
			(drill 1.016)
			(layers "*.Cu" "*.Mask")
			(remove_unused_layers no)
			(net 726 "/HDMI + Ethernet/ETH2_P")
			(pinfunction "TRD2+_1")
			(pintype "passive")
		)
		(pad "4_2" thru_hole circle
			(at 2.031 -8.51 90)
			(size 1.524 1.524)
			(drill 1.016)
			(layers "*.Cu" "*.Mask")
			(remove_unused_layers no)
			(net 856 "/HDMI + Ethernet/GBE3_P")
			(pinfunction "TRD2+_2")
			(pintype "passive")
		)
		(pad "5_1" thru_hole circle
			(at -3.302 -9.779 90)
			(size 1.524 1.524)
			(drill 1.016)
			(layers "*.Cu" "*.Mask")
			(remove_unused_layers no)
			(net 36 "unconnected-(J15A-TRD3-_1-Pad5_1)")
			(pinfunction "TRD3-_1")
			(pintype "passive+no_connect")
		)
		(pad "5_2" thru_hole circle
			(at 3.301 -9.779 90)
			(size 1.524 1.524)
			(drill 1.016)
			(layers "*.Cu" "*.Mask")
			(remove_unused_layers no)
			(net 857 "/HDMI + Ethernet/GBE2_N")
			(pinfunction "TRD3-_2")
			(pintype "passive")
		)
		(pad "6_1" thru_hole circle
			(at -2.032 -11.049 90)
			(size 1.524 1.524)
			(drill 1.016)
			(layers "*.Cu" "*.Mask")
			(remove_unused_layers no)
			(net 39 "unconnected-(J15A-TRD3+_1-Pad6_1)")
			(pinfunction "TRD3+_1")
			(pintype "passive+no_connect")
		)
		(pad "6_2" thru_hole circle
			(at 2.031 -11.049 90)
			(size 1.524 1.524)
			(drill 1.016)
			(layers "*.Cu" "*.Mask")
			(remove_unused_layers no)
			(net 858 "/HDMI + Ethernet/GBE2_P")
			(pinfunction "TRD3+_2")
			(pintype "passive")
		)
		(pad "7_1" thru_hole circle
			(at -3.302 -12.321 90)
			(size 1.524 1.524)
			(drill 1.016)
			(layers "*.Cu" "*.Mask")
			(remove_unused_layers no)
			(net 40 "unconnected-(J15A-TRD4-_1-Pad7_1)")
			(pinfunction "TRD4-_1")
			(pintype "passive+no_connect")
		)
		(pad "7_2" thru_hole circle
			(at 3.301 -12.321 90)
			(size 1.524 1.524)
			(drill 1.016)
			(layers "*.Cu" "*.Mask")
			(remove_unused_layers no)
			(net 859 "/HDMI + Ethernet/GBE1_N")
			(pinfunction "TRD4-_2")
			(pintype "passive")
		)
		(pad "8_1" thru_hole circle
			(at -2.032 -13.59 90)
			(size 1.524 1.524)
			(drill 1.016)
			(layers "*.Cu" "*.Mask")
			(remove_unused_layers no)
			(net 41 "unconnected-(J15A-TRD4+_1-Pad8_1)")
			(pinfunction "TRD4+_1")
			(pintype "passive+no_connect")
		)
		(pad "8_2" thru_hole circle
			(at 2.031 -13.59 90)
			(size 1.524 1.524)
			(drill 1.016)
			(layers "*.Cu" "*.Mask")
			(remove_unused_layers no)
			(net 860 "/HDMI + Ethernet/GBE1_P")
			(pinfunction "TRD4+_2")
			(pintype "passive")
		)
		(pad "9_1" thru_hole circle
			(at -3.302 -14.859 90)
			(size 1.524 1.524)
			(drill 1.016)
			(layers "*.Cu" "*.Mask")
			(remove_unused_layers no)
			(net 12 "Net-(J15A-TRDCT1{slash}2{slash}3{slash}4_1)")
			(pinfunction "TRDCT1/2/3/4_1")
			(pintype "passive")
		)
		(pad "9_2" thru_hole circle
			(at 3.301 -14.859 90)
			(size 1.524 1.524)
			(drill 1.016)
			(layers "*.Cu" "*.Mask")
			(remove_unused_layers no)
			(net 730 "/HDMI + Ethernet/GBE_CONN_COMM")
			(pinfunction "TRDCT1/2/3/4_2")
			(pintype "passive")
		)
		(pad "10_1" thru_hole circle
			(at -2.032 -16.13 90)
			(size 1.524 1.524)
			(drill 1.016)
			(layers "*.Cu" "*.Mask")
			(remove_unused_layers no)
			(net 1 "GND")
			(pinfunction "GND_1")
			(pintype "power_in")
		)
		(pad "10_2" thru_hole circle
			(at 2.031 -16.13 90)
			(size 1.524 1.524)
			(drill 1.016)
			(layers "*.Cu" "*.Mask")
			(remove_unused_layers no)
			(net 1 "GND")
			(pinfunction "GND_2")
			(pintype "passive")
		)
		(pad "11_1" thru_hole circle
			(at -3.302 -19.939 90)
			(size 1.524 1.524)
			(drill 1.016)
			(layers "*.Cu" "*.Mask")
			(remove_unused_layers no)
			(net 765 "/HDMI + Ethernet/POE_ETH.VC2")
			(pinfunction "VC36_1")
			(pintype "passive")
		)
		(pad "11_2" thru_hole circle
			(at 3.301 -19.939 90)
			(size 1.524 1.524)
			(drill 1.016)
			(layers "*.Cu" "*.Mask")
			(remove_unused_layers no)
			(net 759 "/HDMI + Ethernet/POE_GBE.VC2")
			(pinfunction "VC36_2")
			(pintype "passive")
		)
		(pad "12_1" thru_hole circle
			(at -2.032 -21.209 90)
			(size 1.524 1.524)
			(drill 1.016)
			(layers "*.Cu" "*.Mask")
			(remove_unused_layers no)
			(net 766 "/HDMI + Ethernet/POE_ETH.VC3")
			(pinfunction "VC45_1")
			(pintype "passive")
		)
		(pad "12_2" thru_hole circle
			(at 2.031 -21.209 90)
			(size 1.524 1.524)
			(drill 1.016)
			(layers "*.Cu" "*.Mask")
			(remove_unused_layers no)
			(net 760 "/HDMI + Ethernet/POE_GBE.VC3")
			(pinfunction "VC45_2")
			(pintype "passive")
		)
		(pad "13_1" thru_hole circle
			(at -3.302 -22.479 90)
			(size 1.524 1.524)
			(drill 1.016)
			(layers "*.Cu" "*.Mask")
			(remove_unused_layers no)
			(net 767 "/HDMI + Ethernet/POE_ETH.VC4")
			(pinfunction "VC78_1")
			(pintype "passive")
		)
		(pad "13_2" thru_hole circle
			(at 3.301 -22.479 90)
			(size 1.524 1.524)
			(drill 1.016)
			(layers "*.Cu" "*.Mask")
			(remove_unused_layers no)
			(net 761 "/HDMI + Ethernet/POE_GBE.VC4")
			(pinfunction "VC78_2")
			(pintype "passive")
		)
		(pad "14_1" thru_hole circle
			(at -2.032 -23.749 90)
			(size 1.524 1.524)
			(drill 1.016)
			(layers "*.Cu" "*.Mask")
			(remove_unused_layers no)
			(net 764 "/HDMI + Ethernet/POE_ETH.VC1")
			(pinfunction "VC12_1")
			(pintype "passive")
		)
		(pad "14_2" thru_hole circle
			(at 2.031 -23.749 90)
			(size 1.524 1.524)
			(drill 1.016)
			(layers "*.Cu" "*.Mask")
			(remove_unused_layers no)
			(net 758 "/HDMI + Ethernet/POE_GBE.VC1")
			(pinfunction "VC12_2")
			(pintype "passive")
		)
		(pad "15_1" thru_hole circle
			(at -6.986 2.894 90)
			(size 1.62 1.62)
			(drill 1.143)
			(layers "*.Cu" "*.Mask")
			(remove_unused_layers no)
			(net 845 "/HDMI + Ethernet/ETH_LED_LINK+")
			(pintype "passive")
		)
		(pad "15_2" thru_hole circle
			(at -6.986 -11.786 90)
			(size 1.7145 1.7145)
			(drill 1.143)
			(layers "*.Cu" "*.Mask")
			(remove_unused_layers no)
			(net 849 "/HDMI + Ethernet/GBE_LED_LINK+")
			(pintype "passive")
		)
		(pad "16_1" thru_hole circle
			(at -4.446 2.894 90)
			(size 1.62 1.62)
			(drill 1.143)
			(layers "*.Cu" "*.Mask")
			(remove_unused_layers no)
			(net 847 "/HDMI + Ethernet/ETH_LED_LINK-")
			(pintype "passive")
		)
		(pad "16_2" thru_hole circle
			(at -6.986 -5.436 90)
			(size 1.7145 1.7145)
			(drill 1.143)
			(layers "*.Cu" "*.Mask")
			(remove_unused_layers no)
			(net 851 "/HDMI + Ethernet/GBE_LED_LINK-")
			(pintype "passive")
		)
		(pad "17_1" thru_hole circle
			(at 4.445 2.894 90)
			(size 1.62 1.62)
			(drill 1.143)
			(layers "*.Cu" "*.Mask")
			(remove_unused_layers no)
			(net 846 "/HDMI + Ethernet/ETH_LED_SPD-")
			(pintype "passive")
		)
		(pad "17_2" thru_hole circle
			(at 6.985 -7.976 90)
			(size 1.7145 1.7145)
			(drill 1.143)
			(layers "*.Cu" "*.Mask")
			(remove_unused_layers no)
			(net 850 "/HDMI + Ethernet/GBE_LED_SPD-")
			(pintype "passive")
		)
		(pad "18_1" thru_hole circle
			(at 6.985 2.894 90)
			(size 1.62 1.62)
			(drill 1.143)
			(layers "*.Cu" "*.Mask")
			(remove_unused_layers no)
			(net 848 "/HDMI + Ethernet/ETH_LED_SPD+")
			(pintype "passive")
		)
		(pad "18_2" thru_hole circle
			(at 6.985 -5.436 90)
			(size 1.7145 1.7145)
			(drill 1.143)
			(layers "*.Cu" "*.Mask")
			(remove_unused_layers no)
			(net 852 "/HDMI + Ethernet/GBE_LED_SPD+")
			(pintype "passive")
		)
		(pad "SH" thru_hole circle
			(at -8.51 -25.781 90)
			(size 2.3622 2.3622)
			(drill 1.5748)
			(layers "*.Cu" "*.Mask")
			(remove_unused_layers no)
			(net 723 "/HDMI + Ethernet/ETH_CONN_SH")
			(pinfunction "SHIELD")
			(pintype "passive")
		)
		(pad "SH" thru_hole circle
			(at -8.51 -15.494 90)
			(size 2.3622 2.3622)
			(drill 1.5748)
			(layers "*.Cu" "*.Mask")
			(remove_unused_layers no)
			(net 723 "/HDMI + Ethernet/ETH_CONN_SH")
			(pinfunction "SHIELD")
			(pintype "passive")
		)
		(pad "SH" thru_hole circle
			(at -8.51 4.57 90)
			(size 2.3622 2.3622)
			(drill 1.5748)
			(layers "*.Cu" "*.Mask")
			(remove_unused_layers no)
			(net 723 "/HDMI + Ethernet/ETH_CONN_SH")
			(pinfunction "SHIELD")
			(pintype "passive")
		)
		(pad "SH" thru_hole circle
			(at 8.509 -25.781 90)
			(size 2.3622 2.3622)
			(drill 1.5748)
			(layers "*.Cu" "*.Mask")
			(remove_unused_layers no)
			(net 723 "/HDMI + Ethernet/ETH_CONN_SH")
			(pinfunction "SHIELD")
			(pintype "passive")
		)
		(pad "SH" thru_hole circle
			(at 8.509 -11.43 90)
			(size 2.3622 2.3622)
			(drill 1.5748)
			(layers "*.Cu" "*.Mask")
			(remove_unused_layers no)
			(net 723 "/HDMI + Ethernet/ETH_CONN_SH")
			(pinfunction "SHIELD")
			(pintype "passive")
		)
		(pad "SH" thru_hole circle
			(at 8.509 4.57 90)
			(size 2.3622 2.3622)
			(drill 1.5748)
			(layers "*.Cu" "*.Mask")
			(remove_unused_layers no)
			(net 723 "/HDMI + Ethernet/ETH_CONN_SH")
			(pinfunction "SHIELD")
			(pintype "passive")
		)
		(zone
			(net 0)
			(net_name "")
			(layer "F.Cu")
			(hatch full 0.508)
			(connect_pads
				(clearance 0)
			)
			(min_thickness 0.01)
			(filled_areas_thickness no)
			(keepout
				(tracks not_allowed)
				(vias allowed)
				(pads allowed)
				(copperpour not_allowed)
				(footprints allowed)
			)
			(placement
				(enabled no)
				(sheetname "")
			)
			(fill
				(thermal_gap 0.508)
				(thermal_bridge_width 0.508)
			)
			(polygon
				(pts
					(xy 258.832 161.5) (xy 272.294 161.5) (xy 272.294 152.103) (xy 233.899 152.103) (xy 233.899 155.914)
					(xy 258.832 155.914)
				)
			)
		)
		(zone
			(net 0)
			(net_name "")
			(layer "F.Cu")
			(hatch full 0.508)
			(connect_pads
				(clearance 0)
			)
			(min_thickness 0.01)
			(filled_areas_thickness no)
			(keepout
				(tracks not_allowed)
				(vias allowed)
				(pads allowed)
				(copperpour not_allowed)
				(footprints allowed)
			)
			(placement
				(enabled no)
				(sheetname "")
			)
			(fill
				(thermal_gap 0.508)
				(thermal_bridge_width 0.508)
			)
			(polygon
				(pts
					(xy 258.832 161.5) (xy 272.294 161.5) (xy 272.294 170.898) (xy 233.899 170.898) (xy 233.899 167.088)
					(xy 258.832 167.088)
				)
			)
		)
	)
)
